(kicad_pcb
	(version 20241229)
	(generator "pcbnew")
	(generator_version "9.0")
	(general
		(thickness 1.292)
		(legacy_teardrops no)
	)
	(paper "A4")
	(title_block
		(title "LPDDR5 Testbed")
		(date "2023-12-19")
		(rev "1.0.0")
		(comment 9 "footprint 12 of 160 (U1), pads 275-315 of 315")
	)
	(layers
		(0 "F.Cu" signal)
		(4 "In1.Cu" power)
		(6 "In2.Cu" power)
		(8 "In3.Cu" signal)
		(10 "In4.Cu" signal)
		(2 "B.Cu" signal)
		(9 "F.Adhes" user "F.Adhesive")
		(11 "B.Adhes" user "B.Adhesive")
		(13 "F.Paste" user)
		(15 "B.Paste" user)
		(5 "F.SilkS" user "F.Silkscreen")
		(7 "B.SilkS" user "B.Silkscreen")
		(1 "F.Mask" user)
		(3 "B.Mask" user)
		(17 "Dwgs.User" user "User.Drawings")
		(19 "Cmts.User" user "User.Comments")
		(21 "Eco1.User" user "User.Eco1")
		(23 "Eco2.User" user "User.Eco2")
		(25 "Edge.Cuts" user)
		(27 "Margin" user)
		(31 "F.CrtYd" user "F.Courtyard")
		(29 "B.CrtYd" user "B.Courtyard")
		(35 "F.Fab" user)
		(33 "B.Fab" user)
	)
	(footprint "antmicro-footprints:BGA-315_12.4x15mm_Layout15x21_P0.8x0.7mm"
		(layer "F.Cu")
		(at 134.775 80 90)
		(property "Reference" "U1"
			(at 6.8 7.025 0)
			(unlocked yes)
			(layer "F.SilkS")
			(effects
				(font
					(size 0.7 0.7)
					(thickness 0.15)
				)
				(justify left bottom)
			)
		)
		(property "Value" "MT62F1G32D4DR-031"
			(at 0 8.9 90)
			(layer "F.Fab")
			(effects
				(font
					(size 0.7 0.7)
					(thickness 0.15)
				)
				(justify left bottom)
			)
		)
		(property "Author" "Antmicro"
			(at 214.775 -54.775 0)
			(layer "F.Fab")
			(hide yes)
			(effects
				(font
					(size 1 1)
					(thickness 0.15)
				)
			)
		)
		(property "License" "Apache-2.0"
			(at 214.775 -54.775 0)
			(layer "F.Fab")
			(hide yes)
			(effects
				(font
					(size 1 1)
					(thickness 0.15)
				)
			)
		)
		(property "MPN" "MT62F1G32D4DR-031 WT:B"
			(at 214.775 -54.775 0)
			(layer "F.Fab")
			(hide yes)
			(effects
				(font
					(size 1 1)
					(thickness 0.15)
				)
			)
		)
		(property "Manufacturer" "Micron Technology"
			(at 214.775 -54.775 0)
			(layer "F.Fab")
			(hide yes)
			(effects
				(font
					(size 1 1)
					(thickness 0.15)
				)
			)
		)
		(sheetname "LPDDR5")
		(sheetfile "lpddr5.kicad_sch")
		(attr smd)
		(pad "V5" smd circle
			(at -2.4 4.9 90)
			(size 0.41 0.41)
			(layers "F.Cu" "F.Mask" "F.Paste")
			(net 110 "/LPDDR5/LPDDR5_B.WCK1_N")
			(pinfunction "WCK1_c_B")
			(pintype "passive")
		)
		(pad "V6" smd circle
			(at -1.6 4.9 90)
			(size 0.41 0.41)
			(layers "F.Cu" "F.Mask" "F.Paste")
			(net 14 "GND")
			(pinfunction "VSS")
			(pintype "passive")
		)
		(pad "V7" smd circle
			(at -0.8 4.9 90)
			(size 0.41 0.41)
			(layers "F.Cu" "F.Mask" "F.Paste")
			(net 14 "GND")
			(pinfunction "VSS")
			(pintype "passive")
		)
		(pad "V8" smd circle
			(at 0 4.9 90)
			(size 0.41 0.41)
			(layers "F.Cu" "F.Mask" "F.Paste")
			(net 13 "+1V05")
			(pinfunction "VDD2H")
			(pintype "passive")
		)
		(pad "V9" smd circle
			(at 0.8 4.9 90)
			(size 0.41 0.41)
			(layers "F.Cu" "F.Mask" "F.Paste")
			(net 14 "GND")
			(pinfunction "VSS")
			(pintype "passive")
		)
		(pad "V10" smd circle
			(at 1.6 4.9 90)
			(size 0.41 0.41)
			(layers "F.Cu" "F.Mask" "F.Paste")
			(net 14 "GND")
			(pinfunction "VSS")
			(pintype "passive")
		)
		(pad "V11" smd circle
			(at 2.4 4.9 90)
			(size 0.41 0.41)
			(layers "F.Cu" "F.Mask" "F.Paste")
			(net 109 "/LPDDR5/LPDDR5_B.WCK0_N")
			(pinfunction "WCK0_c_B")
			(pintype "passive")
		)
		(pad "V12" smd circle
			(at 3.2 4.9 90)
			(size 0.41 0.41)
			(layers "F.Cu" "F.Mask" "F.Paste")
			(net 4 "+0V5")
			(pinfunction "VDDQ")
			(pintype "passive")
		)
		(pad "V13" smd circle
			(at 4 4.9 90)
			(size 0.41 0.41)
			(layers "F.Cu" "F.Mask" "F.Paste")
			(net 224 "/LPDDR5/LPDDR5_B.DQ3")
			(pinfunction "DQ3_B")
			(pintype "passive")
		)
		(pad "V14" smd circle
			(at 4.8 4.9 90)
			(size 0.41 0.41)
			(layers "F.Cu" "F.Mask" "F.Paste")
			(net 14 "GND")
			(pinfunction "VSS")
			(pintype "passive")
		)
		(pad "V15" smd circle
			(at 5.6 4.9 90)
			(size 0.41 0.41)
			(layers "F.Cu" "F.Mask" "F.Paste")
			(net 227 "/LPDDR5/LPDDR5_B.DQ0")
			(pinfunction "DQ0_B")
			(pintype "passive")
		)
		(pad "W1" smd circle
			(at -5.6 5.6 90)
			(size 0.41 0.41)
			(layers "F.Cu" "F.Mask" "F.Paste")
			(net 35 "+1V8")
			(pinfunction "VDD1")
			(pintype "passive")
		)
		(pad "W2" smd circle
			(at -4.8 5.6 90)
			(size 0.41 0.41)
			(layers "F.Cu" "F.Mask" "F.Paste")
			(net 207 "/LPDDR5/LPDDR5_B.DQ9")
			(pinfunction "DQ9_B")
			(pintype "passive")
		)
		(pad "W3" smd circle
			(at -4 5.6 90)
			(size 0.41 0.41)
			(layers "F.Cu" "F.Mask" "F.Paste")
			(net 4 "+0V5")
			(pinfunction "VDDQ")
			(pintype "passive")
		)
		(pad "W4" smd circle
			(at -3.2 5.6 90)
			(size 0.41 0.41)
			(layers "F.Cu" "F.Mask" "F.Paste")
			(net 210 "/LPDDR5/LPDDR5_B.RDQS1_N")
			(pinfunction "RDQS1_c_B")
			(pintype "passive")
		)
		(pad "W5" smd circle
			(at -2.4 5.6 90)
			(size 0.41 0.41)
			(layers "F.Cu" "F.Mask" "F.Paste")
			(net 14 "GND")
			(pinfunction "VSS")
			(pintype "passive")
		)
		(pad "W6" smd circle
			(at -1.6 5.6 90)
			(size 0.41 0.41)
			(layers "F.Cu" "F.Mask" "F.Paste")
			(net 214 "/LPDDR5/LPDDR5_B.DQ13")
			(pinfunction "DQ13_B")
			(pintype "passive")
		)
		(pad "W7" smd circle
			(at -0.8 5.6 90)
			(size 0.41 0.41)
			(layers "F.Cu" "F.Mask" "F.Paste")
			(net 13 "+1V05")
			(pinfunction "VDD2H")
			(pintype "passive")
		)
		(pad "W8" smd circle
			(at 0 5.6 90)
			(size 0.41 0.41)
			(layers "F.Cu" "F.Mask" "F.Paste")
			(net 14 "GND")
			(pinfunction "VSS")
			(pintype "passive")
		)
		(pad "W9" smd circle
			(at 0.8 5.6 90)
			(size 0.41 0.41)
			(layers "F.Cu" "F.Mask" "F.Paste")
			(net 13 "+1V05")
			(pinfunction "VDD2H")
			(pintype "passive")
		)
		(pad "W10" smd circle
			(at 1.6 5.6 90)
			(size 0.41 0.41)
			(layers "F.Cu" "F.Mask" "F.Paste")
			(net 219 "/LPDDR5/LPDDR5_B.DQ5")
			(pinfunction "DQ5_B")
			(pintype "passive")
		)
		(pad "W11" smd circle
			(at 2.4 5.6 90)
			(size 0.41 0.41)
			(layers "F.Cu" "F.Mask" "F.Paste")
			(net 14 "GND")
			(pinfunction "VSS")
			(pintype "passive")
		)
		(pad "W12" smd circle
			(at 3.2 5.6 90)
			(size 0.41 0.41)
			(layers "F.Cu" "F.Mask" "F.Paste")
			(net 221 "/LPDDR5/LPDDR5_B.RDQS0_N")
			(pinfunction "RDQS0_c_B")
			(pintype "passive")
		)
		(pad "W13" smd circle
			(at 4 5.6 90)
			(size 0.41 0.41)
			(layers "F.Cu" "F.Mask" "F.Paste")
			(net 4 "+0V5")
			(pinfunction "VDDQ")
			(pintype "passive")
		)
		(pad "W14" smd circle
			(at 4.8 5.6 90)
			(size 0.41 0.41)
			(layers "F.Cu" "F.Mask" "F.Paste")
			(net 226 "/LPDDR5/LPDDR5_B.DQ1")
			(pinfunction "DQ1_B")
			(pintype "passive")
		)
		(pad "W15" smd circle
			(at 5.6 5.6 90)
			(size 0.41 0.41)
			(layers "F.Cu" "F.Mask" "F.Paste")
			(net 35 "+1V8")
			(pinfunction "VDD1")
			(pintype "passive")
		)
		(pad "Y1" smd circle
			(at -5.6 6.3 90)
			(size 0.41 0.41)
			(layers "F.Cu" "F.Mask" "F.Paste")
			(net 36 "unconnected-(U1-PadY1)")
			(pinfunction "NC")
			(pintype "no_connect")
		)
		(pad "Y2" smd circle
			(at -4.8 6.3 90)
			(size 0.41 0.41)
			(layers "F.Cu" "F.Mask" "F.Paste")
			(net 4 "+0V5")
			(pinfunction "VDDQ")
			(pintype "passive")
		)
		(pad "Y3" smd circle
			(at -4 6.3 90)
			(size 0.41 0.41)
			(layers "F.Cu" "F.Mask" "F.Paste")
			(net 211 "/LPDDR5/LPDDR5_B.RDQS1_P")
			(pinfunction "RDQS1_t_B")
			(pintype "passive")
		)
		(pad "Y4" smd circle
			(at -3.2 6.3 90)
			(size 0.41 0.41)
			(layers "F.Cu" "F.Mask" "F.Paste")
			(net 14 "GND")
			(pinfunction "VSS")
			(pintype "passive")
		)
		(pad "Y5" smd circle
			(at -2.4 6.3 90)
			(size 0.41 0.41)
			(layers "F.Cu" "F.Mask" "F.Paste")
			(net 213 "/LPDDR5/LPDDR5_B.DQ12")
			(pinfunction "DQ12_B")
			(pintype "passive")
		)
		(pad "Y6" smd circle
			(at -1.6 6.3 90)
			(size 0.41 0.41)
			(layers "F.Cu" "F.Mask" "F.Paste")
			(net 12 "+0V9")
			(pinfunction "VDD2L")
			(pintype "passive")
		)
		(pad "Y7" smd circle
			(at -0.8 6.3 90)
			(size 0.41 0.41)
			(layers "F.Cu" "F.Mask" "F.Paste")
			(net 13 "+1V05")
			(pinfunction "VDD2H")
			(pintype "passive")
		)
		(pad "Y8" smd circle
			(at 0 6.3 90)
			(size 0.41 0.41)
			(layers "F.Cu" "F.Mask" "F.Paste")
			(net 14 "GND")
			(pinfunction "VSS")
			(pintype "passive")
		)
		(pad "Y9" smd circle
			(at 0.8 6.3 90)
			(size 0.41 0.41)
			(layers "F.Cu" "F.Mask" "F.Paste")
			(net 13 "+1V05")
			(pinfunction "VDD2H")
			(pintype "passive")
		)
		(pad "Y10" smd circle
			(at 1.6 6.3 90)
			(size 0.41 0.41)
			(layers "F.Cu" "F.Mask" "F.Paste")
			(net 12 "+0V9")
			(pinfunction "VDD2L")
			(pintype "passive")
		)
		(pad "Y11" smd circle
			(at 2.4 6.3 90)
			(size 0.41 0.41)
			(layers "F.Cu" "F.Mask" "F.Paste")
			(net 220 "/LPDDR5/LPDDR5_B.DQ4")
			(pinfunction "DQ4_B")
			(pintype "passive")
		)
		(pad "Y12" smd circle
			(at 3.2 6.3 90)
			(size 0.41 0.41)
			(layers "F.Cu" "F.Mask" "F.Paste")
			(net 14 "GND")
			(pinfunction "VSS")
			(pintype "passive")
		)
		(pad "Y13" smd circle
			(at 4 6.3 90)
			(size 0.41 0.41)
			(layers "F.Cu" "F.Mask" "F.Paste")
			(net 222 "/LPDDR5/LPDDR5_B.RDQS0_P")
			(pinfunction "RDQS0_t_B")
			(pintype "passive")
		)
		(pad "Y14" smd circle
			(at 4.8 6.3 90)
			(size 0.41 0.41)
			(layers "F.Cu" "F.Mask" "F.Paste")
			(net 4 "+0V5")
			(pinfunction "VDDQ")
			(pintype "passive")
		)
		(pad "Y15" smd circle
			(at 5.6 6.3 90)
			(size 0.41 0.41)
			(layers "F.Cu" "F.Mask" "F.Paste")
			(net 37 "unconnected-(U1-PadY15)")
			(pinfunction "NC")
			(pintype "no_connect")
		)
	)
)
